(kicad_pcb
	(version 20260206)
	(generator "pcbnew")
	(generator_version "10.0")
	(general
		(thickness 1.6)
		(legacy_teardrops no)
	)
	(paper "A4")
	(title_block
		(title "03242023_DA0F0TMBIJ0_F0T_Motherboard_J_brd_V01_OCP.brd")
		(comment 1 "Grand Teton / footprints 5849-5855 of 6105")
	)
	(layers
		(0 "F.Cu" signal "TOP")
		(4 "In1.Cu" signal "GND")
		(6 "In2.Cu" signal "IN1")
		(8 "In3.Cu" signal "GND1")
		(10 "In4.Cu" signal "IN2")
		(12 "In5.Cu" signal "GND2")
		(14 "In6.Cu" signal "IN3")
		(16 "In7.Cu" signal "GND3")
		(18 "In8.Cu" signal "VCC")
		(20 "In9.Cu" signal "VCC1")
		(22 "In10.Cu" signal "GND4")
		(24 "In11.Cu" signal "IN4")
		(26 "In12.Cu" signal "GND5")
		(28 "In13.Cu" signal "IN5")
		(30 "In14.Cu" signal "GND6")
		(32 "In15.Cu" signal "IN6")
		(34 "In16.Cu" signal "GND7")
		(2 "B.Cu" signal "BOTTOM")
		(9 "F.Adhes" user "F.Adhesive")
		(11 "B.Adhes" user "B.Adhesive")
		(13 "F.Paste" user "Package Geometry/Pastemask Top")
		(15 "B.Paste" user "Package Geometry/Pastemask Bottom")
		(5 "F.SilkS" user "Ref Des/Silkscreen Top")
		(7 "B.SilkS" user "Ref Des/Silkscreen Bottom")
		(1 "F.Mask" user "Board Geometry/Soldermask Top")
		(3 "B.Mask" user "Board Geometry/Soldermask Bottom")
		(17 "Dwgs.User" user "User.Drawings")
		(19 "Cmts.User" user "User.Comments")
		(21 "Eco1.User" user "User.Eco1")
		(23 "Eco2.User" user "User.Eco2")
		(25 "Edge.Cuts" user "Board Geometry/Outline")
		(27 "Margin" user)
		(31 "F.CrtYd" user "Package Geometry/Place Bound Top")
		(29 "B.CrtYd" user "Package Geometry/Place Bound Bottom")
		(35 "F.Fab" user "Ref Des/Assembly Top")
		(33 "B.Fab" user "Ref Des/Assembly Bottom")
	)
	(footprint ""
		(layer "B.Cu")
		(at 178.323748 -319.022476 90)
		(property "Reference" "R2736"
			(at 0 0 90)
			(layer "B.SilkS")
			(hide yes)
			(effects
				(font
					(size 1.27 1.27)
				)
				(justify mirror)
			)
		)
		(property "Value" ""
			(at 0 0 90)
			(layer "B.Fab")
			(effects
				(font
					(size 1.27 1.27)
				)
				(justify mirror)
			)
		)
		(duplicate_pad_numbers_are_jumpers no)
		(fp_line
			(start 0.7874 -0.4064)
			(end -0.7874 -0.4064)
			(stroke
				(width 0.1524)
				(type default)
			)
			(layer "B.SilkS")
		)
		(fp_line
			(start -0.7874 -0.4064)
			(end -0.7874 0.4064)
			(stroke
				(width 0.1524)
				(type default)
			)
			(layer "B.SilkS")
		)
		(fp_line
			(start 0.7874 0.4064)
			(end 0.7874 -0.4064)
			(stroke
				(width 0.1524)
				(type default)
			)
			(layer "B.SilkS")
		)
		(fp_line
			(start -0.7874 0.4064)
			(end 0.7874 0.4064)
			(stroke
				(width 0.1524)
				(type default)
			)
			(layer "B.SilkS")
		)
		(fp_line
			(start 0.67945 -0.305054)
			(end 0.12065 -0.305054)
			(stroke
				(width 0.1)
				(type default)
			)
			(layer "B.Fab")
		)
		(fp_line
			(start 0.12065 -0.305054)
			(end 0.12065 -0.2794)
			(stroke
				(width 0.1)
				(type default)
			)
			(layer "B.Fab")
		)
		(fp_line
			(start -0.12065 -0.3048)
			(end -0.67945 -0.3048)
			(stroke
				(width 0.1)
				(type default)
			)
			(layer "B.Fab")
		)
		(fp_line
			(start -0.67945 -0.3048)
			(end -0.67945 0.3048)
			(stroke
				(width 0.1)
				(type default)
			)
			(layer "B.Fab")
		)
		(fp_line
			(start 0.12065 -0.2794)
			(end -0.12065 -0.2794)
			(stroke
				(width 0.1)
				(type default)
			)
			(layer "B.Fab")
		)
		(fp_line
			(start -0.12065 -0.2794)
			(end -0.12065 -0.3048)
			(stroke
				(width 0.1)
				(type default)
			)
			(layer "B.Fab")
		)
		(fp_line
			(start 0.12065 0.2794)
			(end 0.12065 0.3048)
			(stroke
				(width 0.1)
				(type default)
			)
			(layer "B.Fab")
		)
		(fp_line
			(start -0.120396 0.2794)
			(end 0.12065 0.2794)
			(stroke
				(width 0.1)
				(type default)
			)
			(layer "B.Fab")
		)
		(fp_line
			(start 0.67945 0.3048)
			(end 0.67945 -0.305054)
			(stroke
				(width 0.1)
				(type default)
			)
			(layer "B.Fab")
		)
		(fp_line
			(start 0.12065 0.3048)
			(end 0.67945 0.3048)
			(stroke
				(width 0.1)
				(type default)
			)
			(layer "B.Fab")
		)
		(fp_line
			(start -0.120396 0.3048)
			(end -0.120396 0.2794)
			(stroke
				(width 0.1)
				(type default)
			)
			(layer "B.Fab")
		)
		(fp_line
			(start -0.67945 0.3048)
			(end -0.120396 0.3048)
			(stroke
				(width 0.1)
				(type default)
			)
			(layer "B.Fab")
		)
		(pad "1" smd circle
			(at 0.40005 0 270)
			(size 0 0)
			(layers "B.Cu" "B.Mask" "B.Paste")
			(net "PWRGD_CHF_CPU1_DIMM2")
		)
		(pad "2" smd circle
			(at -0.40005 0 270)
			(size 0 0)
			(layers "B.Cu" "B.Mask" "B.Paste")
			(net "PWRGD_FAIL_CPU1_EF")
		)
	)
	(footprint ""
		(layer "B.Cu")
		(at 104.790494 -237.794292 -90)
		(property "Reference" "C1393"
			(at 0 0 90)
			(layer "B.SilkS")
			(hide yes)
			(effects
				(font
					(size 1.27 1.27)
				)
				(justify mirror)
			)
		)
		(property "Value" ""
			(at 0 0 90)
			(layer "B.Fab")
			(effects
				(font
					(size 1.27 1.27)
				)
				(justify mirror)
			)
		)
		(duplicate_pad_numbers_are_jumpers no)
		(fp_line
			(start -1.2954 0.5842)
			(end 1.2954 0.5842)
			(stroke
				(width 0.1524)
				(type default)
			)
			(layer "B.SilkS")
		)
		(fp_line
			(start 1.2954 0.5842)
			(end 1.2954 -0.5842)
			(stroke
				(width 0.1524)
				(type default)
			)
			(layer "B.SilkS")
		)
		(fp_line
			(start -1.2954 -0.5842)
			(end -1.2954 0.5842)
			(stroke
				(width 0.1524)
				(type default)
			)
			(layer "B.SilkS")
		)
		(fp_line
			(start 0 -0.5842)
			(end 0 0.5842)
			(stroke
				(width 0.1524)
				(type default)
			)
			(layer "B.SilkS")
		)
		(fp_line
			(start 1.2954 -0.5842)
			(end -1.2954 -0.5842)
			(stroke
				(width 0.1524)
				(type default)
			)
			(layer "B.SilkS")
		)
		(fp_line
			(start -0.8636 0.4572)
			(end 0.8636 0.4572)
			(stroke
				(width 0.1)
				(type default)
			)
			(layer "B.Fab")
		)
		(fp_line
			(start 0.8636 0.4572)
			(end 0.8636 0.4064)
			(stroke
				(width 0.1)
				(type default)
			)
			(layer "B.Fab")
		)
		(fp_line
			(start -1.1938 0.4064)
			(end -0.8636 0.4064)
			(stroke
				(width 0.1)
				(type default)
			)
			(layer "B.Fab")
		)
		(fp_line
			(start -0.8636 0.4064)
			(end -0.8636 0.4572)
			(stroke
				(width 0.1)
				(type default)
			)
			(layer "B.Fab")
		)
		(fp_line
			(start 0.8636 0.4064)
			(end 1.1938 0.4064)
			(stroke
				(width 0.1)
				(type default)
			)
			(layer "B.Fab")
		)
		(fp_line
			(start 1.1938 0.4064)
			(end 1.1938 -0.4064)
			(stroke
				(width 0.1)
				(type default)
			)
			(layer "B.Fab")
		)
		(fp_line
			(start -1.1938 -0.4064)
			(end -1.1938 0.4064)
			(stroke
				(width 0.1)
				(type default)
			)
			(layer "B.Fab")
		)
		(fp_line
			(start -0.8636 -0.4064)
			(end -1.1938 -0.4064)
			(stroke
				(width 0.1)
				(type default)
			)
			(layer "B.Fab")
		)
		(fp_line
			(start 0.8636 -0.4064)
			(end 0.8636 -0.4572)
			(stroke
				(width 0.1)
				(type default)
			)
			(layer "B.Fab")
		)
		(fp_line
			(start 1.1938 -0.4064)
			(end 0.8636 -0.4064)
			(stroke
				(width 0.1)
				(type default)
			)
			(layer "B.Fab")
		)
		(fp_line
			(start -0.8636 -0.4572)
			(end -0.8636 -0.4064)
			(stroke
				(width 0.1)
				(type default)
			)
			(layer "B.Fab")
		)
		(fp_line
			(start 0.8636 -0.4572)
			(end -0.8636 -0.4572)
			(stroke
				(width 0.1)
				(type default)
			)
			(layer "B.Fab")
		)
		(pad "1" smd rect
			(at 0.7366 0 180)
			(size 0.7112 0.8128)
			(layers "B.Cu" "B.Mask" "B.Paste")
			(net "PVNN_MAIN_CPU1")
		)
		(pad "2" smd rect
			(at -0.7366 0 180)
			(size 0.7112 0.8128)
			(layers "B.Cu" "B.Mask" "B.Paste")
			(net "GND")
		)
	)
	(footprint ""
		(layer "B.Cu")
		(at 433.832 -24.094948 -90)
		(property "Reference" "R1897"
			(at 0 0 90)
			(layer "B.SilkS")
			(hide yes)
			(effects
				(font
					(size 1.27 1.27)
				)
				(justify mirror)
			)
		)
		(property "Value" ""
			(at 0 0 90)
			(layer "B.Fab")
			(effects
				(font
					(size 1.27 1.27)
				)
				(justify mirror)
			)
		)
		(duplicate_pad_numbers_are_jumpers no)
		(fp_line
			(start -0.7874 0.4064)
			(end 0.7874 0.4064)
			(stroke
				(width 0.1524)
				(type default)
			)
			(layer "B.SilkS")
		)
		(fp_line
			(start 0.7874 0.4064)
			(end 0.7874 -0.4064)
			(stroke
				(width 0.1524)
				(type default)
			)
			(layer "B.SilkS")
		)
		(fp_line
			(start -0.7874 -0.4064)
			(end -0.7874 0.4064)
			(stroke
				(width 0.1524)
				(type default)
			)
			(layer "B.SilkS")
		)
		(fp_line
			(start 0.7874 -0.4064)
			(end -0.7874 -0.4064)
			(stroke
				(width 0.1524)
				(type default)
			)
			(layer "B.SilkS")
		)
		(fp_line
			(start -0.67945 0.3048)
			(end -0.120396 0.3048)
			(stroke
				(width 0.1)
				(type default)
			)
			(layer "B.Fab")
		)
		(fp_line
			(start -0.120396 0.3048)
			(end -0.120396 0.2794)
			(stroke
				(width 0.1)
				(type default)
			)
			(layer "B.Fab")
		)
		(fp_line
			(start 0.12065 0.3048)
			(end 0.67945 0.3048)
			(stroke
				(width 0.1)
				(type default)
			)
			(layer "B.Fab")
		)
		(fp_line
			(start 0.67945 0.3048)
			(end 0.67945 -0.305054)
			(stroke
				(width 0.1)
				(type default)
			)
			(layer "B.Fab")
		)
		(fp_line
			(start -0.120396 0.2794)
			(end 0.12065 0.2794)
			(stroke
				(width 0.1)
				(type default)
			)
			(layer "B.Fab")
		)
		(fp_line
			(start 0.12065 0.2794)
			(end 0.12065 0.3048)
			(stroke
				(width 0.1)
				(type default)
			)
			(layer "B.Fab")
		)
		(fp_line
			(start -0.12065 -0.2794)
			(end -0.12065 -0.3048)
			(stroke
				(width 0.1)
				(type default)
			)
			(layer "B.Fab")
		)
		(fp_line
			(start 0.12065 -0.2794)
			(end -0.12065 -0.2794)
			(stroke
				(width 0.1)
				(type default)
			)
			(layer "B.Fab")
		)
		(fp_line
			(start -0.67945 -0.3048)
			(end -0.67945 0.3048)
			(stroke
				(width 0.1)
				(type default)
			)
			(layer "B.Fab")
		)
		(fp_line
			(start -0.12065 -0.3048)
			(end -0.67945 -0.3048)
			(stroke
				(width 0.1)
				(type default)
			)
			(layer "B.Fab")
		)
		(fp_line
			(start 0.12065 -0.305054)
			(end 0.12065 -0.2794)
			(stroke
				(width 0.1)
				(type default)
			)
			(layer "B.Fab")
		)
		(fp_line
			(start 0.67945 -0.305054)
			(end 0.12065 -0.305054)
			(stroke
				(width 0.1)
				(type default)
			)
			(layer "B.Fab")
		)
		(pad "1" smd circle
			(at 0.40005 0 90)
			(size 0 0)
			(layers "B.Cu" "B.Mask" "B.Paste")
			(net "OCP_SFF_ISO_BIF1_EN")
		)
		(pad "2" smd circle
			(at -0.40005 0 90)
			(size 0 0)
			(layers "B.Cu" "B.Mask" "B.Paste")
			(net "GND")
		)
	)
	(footprint ""
		(layer "B.Cu")
		(at 62.666372 -168.58488)
		(property "Reference" "PC382"
			(at 0 0 0)
			(layer "B.SilkS")
			(hide yes)
			(effects
				(font
					(size 1.27 1.27)
				)
				(justify mirror)
			)
		)
		(property "Value" ""
			(at 0 0 0)
			(layer "B.Fab")
			(effects
				(font
					(size 1.27 1.27)
				)
				(justify mirror)
			)
		)
		(duplicate_pad_numbers_are_jumpers no)
		(fp_line
			(start -1.524 -0.762)
			(end -1.524 0.762)
			(stroke
				(width 0.1524)
				(type default)
			)
			(layer "B.SilkS")
		)
		(fp_line
			(start -1.524 0.762)
			(end 1.524 0.762)
			(stroke
				(width 0.1524)
				(type default)
			)
			(layer "B.SilkS")
		)
		(fp_line
			(start 1.524 -0.762)
			(end -1.524 -0.762)
			(stroke
				(width 0.1524)
				(type default)
			)
			(layer "B.SilkS")
		)
		(fp_line
			(start 1.524 0.762)
			(end 1.524 -0.762)
			(stroke
				(width 0.1524)
				(type default)
			)
			(layer "B.SilkS")
		)
		(fp_line
			(start -1.1049 -0.724916)
			(end 1.1049 -0.724916)
			(stroke
				(width 0.1)
				(type default)
			)
			(layer "B.Fab")
		)
		(fp_line
			(start -1.1049 0.724916)
			(end -1.1049 -0.724916)
			(stroke
				(width 0.1)
				(type default)
			)
			(layer "B.Fab")
		)
		(fp_line
			(start 1.1049 -0.724916)
			(end 1.1049 0.724916)
			(stroke
				(width 0.1)
				(type default)
			)
			(layer "B.Fab")
		)
		(fp_line
			(start 1.1049 0.724916)
			(end -1.1049 0.724916)
			(stroke
				(width 0.1)
				(type default)
			)
			(layer "B.Fab")
		)
		(pad "1" smd rect
			(at 0.889 0)
			(size 1.016 1.27)
			(layers "B.Cu" "B.Mask" "B.Paste")
			(net "PVCCD_HV_CPU1")
		)
		(pad "2" smd rect
			(at -0.889 0)
			(size 1.016 1.27)
			(layers "B.Cu" "B.Mask" "B.Paste")
			(net "GND")
		)
	)
	(footprint ""
		(layer "B.Cu")
		(at 187.174886 -193.599816 -90)
		(property "Reference" "C616"
			(at 0 0 90)
			(layer "B.SilkS")
			(hide yes)
			(effects
				(font
					(size 1.27 1.27)
				)
				(justify mirror)
			)
		)
		(property "Value" ""
			(at 0 0 90)
			(layer "B.Fab")
			(effects
				(font
					(size 1.27 1.27)
				)
				(justify mirror)
			)
		)
		(duplicate_pad_numbers_are_jumpers no)
		(fp_line
			(start -0.7874 0.4064)
			(end 0.7874 0.4064)
			(stroke
				(width 0.1524)
				(type default)
			)
			(layer "B.SilkS")
		)
		(fp_line
			(start 0.7874 0.4064)
			(end 0.7874 -0.4064)
			(stroke
				(width 0.1524)
				(type default)
			)
			(layer "B.SilkS")
		)
		(fp_line
			(start -0.7874 -0.4064)
			(end -0.7874 0.4064)
			(stroke
				(width 0.1524)
				(type default)
			)
			(layer "B.SilkS")
		)
		(fp_line
			(start 0.7874 -0.4064)
			(end -0.7874 -0.4064)
			(stroke
				(width 0.1524)
				(type default)
			)
			(layer "B.SilkS")
		)
		(fp_line
			(start -0.67945 0.3048)
			(end -0.120396 0.3048)
			(stroke
				(width 0.1)
				(type default)
			)
			(layer "B.Fab")
		)
		(fp_line
			(start -0.120396 0.3048)
			(end -0.120396 0.2794)
			(stroke
				(width 0.1)
				(type default)
			)
			(layer "B.Fab")
		)
		(fp_line
			(start 0.12065 0.3048)
			(end 0.67945 0.3048)
			(stroke
				(width 0.1)
				(type default)
			)
			(layer "B.Fab")
		)
		(fp_line
			(start 0.67945 0.3048)
			(end 0.67945 -0.305054)
			(stroke
				(width 0.1)
				(type default)
			)
			(layer "B.Fab")
		)
		(fp_line
			(start -0.120396 0.2794)
			(end 0.12065 0.2794)
			(stroke
				(width 0.1)
				(type default)
			)
			(layer "B.Fab")
		)
		(fp_line
			(start 0.12065 0.2794)
			(end 0.12065 0.3048)
			(stroke
				(width 0.1)
				(type default)
			)
			(layer "B.Fab")
		)
		(fp_line
			(start -0.12065 -0.2794)
			(end -0.12065 -0.3048)
			(stroke
				(width 0.1)
				(type default)
			)
			(layer "B.Fab")
		)
		(fp_line
			(start 0.12065 -0.2794)
			(end -0.12065 -0.2794)
			(stroke
				(width 0.1)
				(type default)
			)
			(layer "B.Fab")
		)
		(fp_line
			(start -0.67945 -0.3048)
			(end -0.67945 0.3048)
			(stroke
				(width 0.1)
				(type default)
			)
			(layer "B.Fab")
		)
		(fp_line
			(start -0.12065 -0.3048)
			(end -0.67945 -0.3048)
			(stroke
				(width 0.1)
				(type default)
			)
			(layer "B.Fab")
		)
		(fp_line
			(start 0.12065 -0.305054)
			(end 0.12065 -0.2794)
			(stroke
				(width 0.1)
				(type default)
			)
			(layer "B.Fab")
		)
		(fp_line
			(start 0.67945 -0.305054)
			(end 0.12065 -0.305054)
			(stroke
				(width 0.1)
				(type default)
			)
			(layer "B.Fab")
		)
		(pad "1" smd circle
			(at 0.40005 0 90)
			(size 0 0)
			(layers "B.Cu" "B.Mask" "B.Paste")
			(net "RST_PLD_CPU1_DRAM_EF_N")
		)
		(pad "2" smd circle
			(at -0.40005 0 90)
			(size 0 0)
			(layers "B.Cu" "B.Mask" "B.Paste")
			(net "GND")
		)
	)
	(footprint ""
		(layer "B.Cu")
		(at 355.397308 -241.142266 90)
		(property "Reference" "C360"
			(at 0 0 90)
			(layer "B.SilkS")
			(hide yes)
			(effects
				(font
					(size 1.27 1.27)
				)
				(justify mirror)
			)
		)
		(property "Value" ""
			(at 0 0 90)
			(layer "B.Fab")
			(effects
				(font
					(size 1.27 1.27)
				)
				(justify mirror)
			)
		)
		(duplicate_pad_numbers_are_jumpers no)
		(fp_line
			(start 1.524 -0.762)
			(end -1.524 -0.762)
			(stroke
				(width 0.1524)
				(type default)
			)
			(layer "B.SilkS")
		)
		(fp_line
			(start -1.524 -0.762)
			(end -1.524 0.762)
			(stroke
				(width 0.1524)
				(type default)
			)
			(layer "B.SilkS")
		)
		(fp_line
			(start 1.524 0.762)
			(end 1.524 -0.762)
			(stroke
				(width 0.1524)
				(type default)
			)
			(layer "B.SilkS")
		)
		(fp_line
			(start -1.524 0.762)
			(end 1.524 0.762)
			(stroke
				(width 0.1524)
				(type default)
			)
			(layer "B.SilkS")
		)
		(fp_line
			(start 1.1049 -0.724916)
			(end 1.1049 0.724916)
			(stroke
				(width 0.1)
				(type default)
			)
			(layer "B.Fab")
		)
		(fp_line
			(start -1.1049 -0.724916)
			(end 1.1049 -0.724916)
			(stroke
				(width 0.1)
				(type default)
			)
			(layer "B.Fab")
		)
		(fp_line
			(start 1.1049 0.724916)
			(end -1.1049 0.724916)
			(stroke
				(width 0.1)
				(type default)
			)
			(layer "B.Fab")
		)
		(fp_line
			(start -1.1049 0.724916)
			(end -1.1049 -0.724916)
			(stroke
				(width 0.1)
				(type default)
			)
			(layer "B.Fab")
		)
		(pad "1" smd rect
			(at 0.889 0 90)
			(size 1.016 1.27)
			(layers "B.Cu" "B.Mask" "B.Paste")
			(net "PVCCIN_CPU0")
		)
		(pad "2" smd rect
			(at -0.889 0 90)
			(size 1.016 1.27)
			(layers "B.Cu" "B.Mask" "B.Paste")
			(net "GND")
		)
	)
	(footprint ""
		(layer "B.Cu")
		(at 420.682166 -137.178034)
		(property "Reference" "PR106"
			(at 0 0 0)
			(layer "B.SilkS")
			(hide yes)
			(effects
				(font
					(size 1.27 1.27)
				)
				(justify mirror)
			)
		)
		(property "Value" ""
			(at 0 0 0)
			(layer "B.Fab")
			(effects
				(font
					(size 1.27 1.27)
				)
				(justify mirror)
			)
		)
		(duplicate_pad_numbers_are_jumpers no)
		(fp_line
			(start -0.7874 -0.4064)
			(end -0.7874 0.4064)
			(stroke
				(width 0.1524)
				(type default)
			)
			(layer "B.SilkS")
		)
		(fp_line
			(start -0.7874 0.4064)
			(end 0.7874 0.4064)
			(stroke
				(width 0.1524)
				(type default)
			)
			(layer "B.SilkS")
		)
		(fp_line
			(start 0.7874 -0.4064)
			(end -0.7874 -0.4064)
			(stroke
				(width 0.1524)
				(type default)
			)
			(layer "B.SilkS")
		)
		(fp_line
			(start 0.7874 0.4064)
			(end 0.7874 -0.4064)
			(stroke
				(width 0.1524)
				(type default)
			)
			(layer "B.SilkS")
		)
		(fp_line
			(start -0.67945 -0.3048)
			(end -0.67945 0.3048)
			(stroke
				(width 0.1)
				(type default)
			)
			(layer "B.Fab")
		)
		(fp_line
			(start -0.67945 0.3048)
			(end -0.120396 0.3048)
			(stroke
				(width 0.1)
				(type default)
			)
			(layer "B.Fab")
		)
		(fp_line
			(start -0.12065 -0.3048)
			(end -0.67945 -0.3048)
			(stroke
				(width 0.1)
				(type default)
			)
			(layer "B.Fab")
		)
		(fp_line
			(start -0.12065 -0.2794)
			(end -0.12065 -0.3048)
			(stroke
				(width 0.1)
				(type default)
			)
			(layer "B.Fab")
		)
		(fp_line
			(start -0.120396 0.2794)
			(end 0.12065 0.2794)
			(stroke
				(width 0.1)
				(type default)
			)
			(layer "B.Fab")
		)
		(fp_line
			(start -0.120396 0.3048)
			(end -0.120396 0.2794)
			(stroke
				(width 0.1)
				(type default)
			)
			(layer "B.Fab")
		)
		(fp_line
			(start 0.12065 -0.305054)
			(end 0.12065 -0.2794)
			(stroke
				(width 0.1)
				(type default)
			)
			(layer "B.Fab")
		)
		(fp_line
			(start 0.12065 -0.2794)
			(end -0.12065 -0.2794)
			(stroke
				(width 0.1)
				(type default)
			)
			(layer "B.Fab")
		)
		(fp_line
			(start 0.12065 0.2794)
			(end 0.12065 0.3048)
			(stroke
				(width 0.1)
				(type default)
			)
			(layer "B.Fab")
		)
		(fp_line
			(start 0.12065 0.3048)
			(end 0.67945 0.3048)
			(stroke
				(width 0.1)
				(type default)
			)
			(layer "B.Fab")
		)
		(fp_line
			(start 0.67945 -0.305054)
			(end 0.12065 -0.305054)
			(stroke
				(width 0.1)
				(type default)
			)
			(layer "B.Fab")
		)
		(fp_line
			(start 0.67945 0.3048)
			(end 0.67945 -0.305054)
			(stroke
				(width 0.1)
				(type default)
			)
			(layer "B.Fab")
		)
		(pad "1" smd circle
			(at 0.40005 0 180)
			(size 0 0)
			(layers "B.Cu" "B.Mask" "B.Paste")
			(net "PVCCINFAON_CPU0_ADDR")
		)
		(pad "2" smd circle
			(at -0.40005 0 180)
			(size 0 0)
			(layers "B.Cu" "B.Mask" "B.Paste")
			(net "GND")
		)
	)
)
